FILE_TYPE = MULTI_PHYS_TABLE;

PART 'BZA462A'

{========================================================================================}
:VALUE     | PART_TYPE | MATERIAL | PART_NUMBER    = STANDARD | LIFECYCLE      | PART_NUMBER   | JEDEC_TYPE | DESCRIPTION                            | MANUFTR | MANUF_PN  | RD_CMPLS_LVL | CMPLS_LVL | CLASS | DIP_SMD | FP_ECN | FROM_PJ    | DATA              | EE_CHECK_LIST | STATUS | PSL | PREFERENCE | CREATOR | CREATEDAY  | ESD_CDM | ESD_HBM | ESD_MM | MSD | PIN_LENGTH_LONG_PIN | PIN_LENGTH_SHORT_PIN ;
{========================================================================================}
 'BZA462A' | 'SMLF'    | 'IC'     | 'BCZA462AZ01'(!) = ''       | ''               | 'BCZA462AZ01' |'SOT457XA'| 'DIODE SMD BZA462A(6.2V,100MA,SOT457)' | 'PHI'   | 'BZA462A' | 'EP'         | 'EP'      | 'IC'  | ''      | ''     | 'S56-PARK' | 'PHI_BZA462A.pdf' | ''            | ''     | ''  | ''         | ''      | '20100429' | ''      | ''      | ''     | ''  | ''                  | ''                  
 'BZA462A' | 'SMLF'    | 'EMPTY'  | 'BCZA462AZ01'(!) = ''       | ''               | 'BCZA462AZ01' |'SOT457XA'| 'DIODE SMD BZA462A(6.2V,100MA,SOT457)' | 'PHI'   | 'BZA462A' | 'EP'         | 'EP'      | 'IC'  | ''      | ''     | 'S56-PARK' | 'PHI_BZA462A.pdf' | ''            | ''     | ''  | ''         | ''      | '20100429' | ''      | ''      | ''     | ''  | ''                  | ''                  

END_PART

END.

